# S9S_MB_2U (Grand Teton) — schematic netlist excerpt (pin names and nets, part order shuffled) for the footprints in the layout excerpt that follows; sources: Cadence DE-HDL packaged netlist, KiCad conversion of 03242023_DA0F0TMBIJ0_F0T_Motherboard_J_brd_V01_OCP.brd

PU200  MAX15090BEWIT  MAX15090BEWI+T IC  pkg BGA28_0-5_3-525X2-065  page 162
  ISENSE  = P3V3_OCP_SENSE_2
  VCC  = P3V3_OCP_VCC_2
  IN_A3  = P3V3_AUX
  OUT_A4  = P3V3_OCP_V3_2_R
  IN_A5  = P3V3_AUX
  GATE  = P3V3_OCP_GATE_2
  CDLY  = GND
  CB  = P3V3_OCP_CB_2
  GND_B2  = GND
  IN_B3  = P3V3_AUX
  OUT_B4  = P3V3_OCP_V3_2_R
  IN_B5  = P3V3_AUX
  OUT_B6  = P3V3_OCP_V3_2_R
  \en#\  = GND
  GND_C1  = GND
  GND_C2  = GND
  IN_C3  = P3V3_AUX
  OUT_C4  = P3V3_OCP_V3_2_R
  IN_C5  = P3V3_AUX
  OUT_C6  = P3V3_OCP_V3_2_R
  \fault#\  = P3V3_OCP_FAULT_2
  REG  = P3V3_OCP_REG_2
  UV  = P3V3_OCP_UV_2
  OV  = P3V3_OCP_OV_2
  OUT_D4  = P3V3_OCP_V3_2_R
  IN_D5  = P3V3_AUX
  OUT_D6  = P3V3_OCP_V3_2_R
  PG  = P3V3_OCP_PWRGD_2

(kicad_pcb
	(version 20260206)
	(generator "pcbnew")
	(generator_version "10.0")
	(general
		(thickness 1.6)
		(legacy_teardrops no)
	)
	(paper "A4")
	(title_block
		(title "03242023_DA0F0TMBIJ0_F0T_Motherboard_J_brd_V01_OCP.brd")
		(comment 1 "Grand Teton / footprints 4006-4006 of 6105")
	)
	(layers
		(0 "F.Cu" signal "TOP")
		(4 "In1.Cu" signal "GND")
		(6 "In2.Cu" signal "IN1")
		(8 "In3.Cu" signal "GND1")
		(10 "In4.Cu" signal "IN2")
		(12 "In5.Cu" signal "GND2")
		(14 "In6.Cu" signal "IN3")
		(16 "In7.Cu" signal "GND3")
		(18 "In8.Cu" signal "VCC")
		(20 "In9.Cu" signal "VCC1")
		(22 "In10.Cu" signal "GND4")
		(24 "In11.Cu" signal "IN4")
		(26 "In12.Cu" signal "GND5")
		(28 "In13.Cu" signal "IN5")
		(30 "In14.Cu" signal "GND6")
		(32 "In15.Cu" signal "IN6")
		(34 "In16.Cu" signal "GND7")
		(2 "B.Cu" signal "BOTTOM")
		(9 "F.Adhes" user "F.Adhesive")
		(11 "B.Adhes" user "B.Adhesive")
		(13 "F.Paste" user "Package Geometry/Pastemask Top")
		(15 "B.Paste" user "Package Geometry/Pastemask Bottom")
		(5 "F.SilkS" user "Ref Des/Silkscreen Top")
		(7 "B.SilkS" user "Ref Des/Silkscreen Bottom")
		(1 "F.Mask" user "Board Geometry/Soldermask Top")
		(3 "B.Mask" user "Board Geometry/Soldermask Bottom")
		(17 "Dwgs.User" user "User.Drawings")
		(19 "Cmts.User" user "User.Comments")
		(21 "Eco1.User" user "User.Eco1")
		(23 "Eco2.User" user "User.Eco2")
		(25 "Edge.Cuts" user "Board Geometry/Outline")
		(27 "Margin" user)
		(31 "F.CrtYd" user "Package Geometry/Place Bound Top")
		(29 "B.CrtYd" user "Package Geometry/Place Bound Bottom")
		(35 "F.Fab" user "Ref Des/Assembly Top")
		(33 "B.Fab" user "Ref Des/Assembly Bottom")
	)
	(footprint ""
		(layer "F.Cu")
		(at 83.30057 -55.432706 -90)
		(property "Reference" "PU200"
			(at 0.436626 7.02818 0)
			(unlocked yes)
			(layer "F.SilkS")
			(effects
				(font
					(size 0.7874 0.5842)
					(thickness 0.1524)
				)
				(justify left)
			)
		)
		(property "Value" ""
			(at 0 0 270)
			(layer "F.Fab")
			(effects
				(font
					(size 1.27 1.27)
				)
			)
		)
		(duplicate_pad_numbers_are_jumpers no)
		(fp_line
			(start -1.774952 1.039876)
			(end 1.774952 1.039876)
			(stroke
				(width 0.1524)
				(type default)
			)
			(layer "F.SilkS")
		)
		(fp_line
			(start 1.774952 1.039876)
			(end 1.774952 -1.039876)
			(stroke
				(width 0.1524)
				(type default)
			)
			(layer "F.SilkS")
		)
		(fp_line
			(start -1.774952 -1.039876)
			(end -1.774952 1.039876)
			(stroke
				(width 0.1524)
				(type default)
			)
			(layer "F.SilkS")
		)
		(fp_line
			(start 1.774952 -1.039876)
			(end -1.774952 -1.039876)
			(stroke
				(width 0.1524)
				(type default)
			)
			(layer "F.SilkS")
		)
		(fp_poly
			(pts
				(xy -1.769872 -1.039876) (xy -1.769872 -0.249936) (xy -2.531872 -0.249936) (xy -2.531872 -1.801876)
				(xy -0.999998 -1.801876) (xy -0.999998 -1.039876)
			)
			(stroke
				(width 0)
				(type default)
			)
			(fill yes)
			(layer "F.SilkS")
		)
		(fp_line
			(start -1.769872 1.039876)
			(end 1.769872 1.039876)
			(stroke
				(width 0.1)
				(type default)
			)
			(layer "F.Fab")
		)
		(fp_line
			(start 1.769872 1.039876)
			(end 1.769872 -1.039876)
			(stroke
				(width 0.1)
				(type default)
			)
			(layer "F.Fab")
		)
		(fp_line
			(start -1.769872 -1.039876)
			(end -1.769872 1.039876)
			(stroke
				(width 0.1)
				(type default)
			)
			(layer "F.Fab")
		)
		(fp_line
			(start 1.769872 -1.039876)
			(end -1.769872 -1.039876)
			(stroke
				(width 0.1)
				(type default)
			)
			(layer "F.Fab")
		)
		(fp_poly
			(pts
				(xy -1.769872 -1.039876) (xy -0.999998 -1.039876) (xy -0.999998 -1.801876) (xy -2.531872 -1.801876)
				(xy -2.531872 -0.249936) (xy -1.769872 -0.249936)
			)
			(stroke
				(width 0)
				(type default)
			)
			(fill yes)
			(layer "F.Fab")
		)
		(pad "A1" smd circle
			(at -1.500124 -0.750062 270)
			(size 0.2286 0.2286)
			(layers "F.Cu" "F.Mask" "F.Paste")
			(net "P3V3_OCP_SENSE_2")
		)
		(pad "A2" smd circle
			(at -0.999998 -0.750062 270)
			(size 0.2286 0.2286)
			(layers "F.Cu" "F.Mask" "F.Paste")
			(net "P3V3_OCP_VCC_2")
		)
		(pad "A3" smd circle
			(at -0.499872 -0.750062 270)
			(size 0.2286 0.2286)
			(layers "F.Cu" "F.Mask" "F.Paste")
			(net "P3V3_AUX")
		)
		(pad "A4" smd circle
			(at 0 -0.750062 270)
			(size 0.2286 0.2286)
			(layers "F.Cu" "F.Mask" "F.Paste")
			(net "P3V3_OCP_V3_2_R")
		)
		(pad "A5" smd circle
			(at 0.499872 -0.750062 270)
			(size 0.2286 0.2286)
			(layers "F.Cu" "F.Mask" "F.Paste")
			(net "P3V3_AUX")
		)
		(pad "A6" smd circle
			(at 0.999998 -0.750062 270)
			(size 0.2286 0.2286)
			(layers "F.Cu" "F.Mask" "F.Paste")
			(net "P3V3_OCP_GATE_2")
		)
		(pad "A7" smd circle
			(at 1.500124 -0.750062 270)
			(size 0.2286 0.2286)
			(layers "F.Cu" "F.Mask" "F.Paste")
			(net "GND")
		)
		(pad "B1" smd circle
			(at -1.500124 -0.249936 270)
			(size 0.2286 0.2286)
			(layers "F.Cu" "F.Mask" "F.Paste")
			(net "P3V3_OCP_CB_2")
		)
		(pad "B2" smd circle
			(at -0.999998 -0.249936 270)
			(size 0.2286 0.2286)
			(layers "F.Cu" "F.Mask" "F.Paste")
			(net "GND")
		)
		(pad "B3" smd circle
			(at -0.499872 -0.249936 270)
			(size 0.2286 0.2286)
			(layers "F.Cu" "F.Mask" "F.Paste")
			(net "P3V3_AUX")
		)
		(pad "B4" smd circle
			(at 0 -0.249936 270)
			(size 0.2286 0.2286)
			(layers "F.Cu" "F.Mask" "F.Paste")
			(net "P3V3_OCP_V3_2_R")
		)
		(pad "B5" smd circle
			(at 0.499872 -0.249936 270)
			(size 0.2286 0.2286)
			(layers "F.Cu" "F.Mask" "F.Paste")
			(net "P3V3_AUX")
		)
		(pad "B6" smd circle
			(at 0.999998 -0.249936 270)
			(size 0.2286 0.2286)
			(layers "F.Cu" "F.Mask" "F.Paste")
			(net "P3V3_OCP_V3_2_R")
		)
		(pad "B7" smd circle
			(at 1.500124 -0.249936 270)
			(size 0.2286 0.2286)
			(layers "F.Cu" "F.Mask" "F.Paste")
			(net "GND")
		)
		(pad "C1" smd circle
			(at -1.500124 0.249936 270)
			(size 0.2286 0.2286)
			(layers "F.Cu" "F.Mask" "F.Paste")
			(net "GND")
		)
		(pad "C2" smd circle
			(at -0.999998 0.249936 270)
			(size 0.2286 0.2286)
			(layers "F.Cu" "F.Mask" "F.Paste")
			(net "GND")
		)
		(pad "C3" smd circle
			(at -0.499872 0.249936 270)
			(size 0.2286 0.2286)
			(layers "F.Cu" "F.Mask" "F.Paste")
			(net "P3V3_AUX")
		)
		(pad "C4" smd circle
			(at 0 0.249936 270)
			(size 0.2286 0.2286)
			(layers "F.Cu" "F.Mask" "F.Paste")
			(net "P3V3_OCP_V3_2_R")
		)
		(pad "C5" smd circle
			(at 0.499872 0.249936 270)
			(size 0.2286 0.2286)
			(layers "F.Cu" "F.Mask" "F.Paste")
			(net "P3V3_AUX")
		)
		(pad "C6" smd circle
			(at 0.999998 0.249936 270)
			(size 0.2286 0.2286)
			(layers "F.Cu" "F.Mask" "F.Paste")
			(net "P3V3_OCP_V3_2_R")
		)
		(pad "C7" smd circle
			(at 1.500124 0.249936 270)
			(size 0.2286 0.2286)
			(layers "F.Cu" "F.Mask" "F.Paste")
			(net "P3V3_OCP_FAULT_2")
		)
		(pad "D1" smd circle
			(at -1.500124 0.750062 270)
			(size 0.2286 0.2286)
			(layers "F.Cu" "F.Mask" "F.Paste")
			(net "P3V3_OCP_REG_2")
		)
		(pad "D2" smd circle
			(at -0.999998 0.750062 270)
			(size 0.2286 0.2286)
			(layers "F.Cu" "F.Mask" "F.Paste")
			(net "P3V3_OCP_UV_2")
		)
		(pad "D3" smd circle
			(at -0.499872 0.750062 270)
			(size 0.2286 0.2286)
			(layers "F.Cu" "F.Mask" "F.Paste")
			(net "P3V3_OCP_OV_2")
		)
		(pad "D4" smd circle
			(at 0 0.750062 270)
			(size 0.2286 0.2286)
			(layers "F.Cu" "F.Mask" "F.Paste")
			(net "P3V3_OCP_V3_2_R")
		)
		(pad "D5" smd circle
			(at 0.499872 0.750062 270)
			(size 0.2286 0.2286)
			(layers "F.Cu" "F.Mask" "F.Paste")
			(net "P3V3_AUX")
		)
		(pad "D6" smd circle
			(at 0.999998 0.750062 270)
			(size 0.2286 0.2286)
			(layers "F.Cu" "F.Mask" "F.Paste")
			(net "P3V3_OCP_V3_2_R")
		)
		(pad "D7" smd circle
			(at 1.500124 0.750062 270)
			(size 0.2286 0.2286)
			(layers "F.Cu" "F.Mask" "F.Paste")
			(net "P3V3_OCP_PWRGD_2")
		)
	)
)
